FILE_TYPE = MACRO_DRAWING;
SET COLOR_WIRE YELLOW;
SET COLOR_PROP ORANGE;
SET COLOR_DOT WHITE;
SET COLOR_ARC YELLOW;
SET COLOR_BODY GREEN;
SET COLOR_NOTE PURPLE;
SET PROP_DISPLAY VALUE;
SET PAGE_NUMBER P290;
FORCEADD ME_DUMMY_SYMBOL..1
(3600 3275);
FORCEPROP 1 LAST PART_NUMBER DUMMY48
J 0
(3406 3472);
DISPLAY 0.723404 (3406 3472);
PAINT GREEN (3406 3472);
DISPLAY INVISIBLE (3406 3472);
FORCEPROP 2 LAST PART_TYPE MECH
J 0
(3425 3625);
DISPLAY 0.808511 (3425 3625);
FORCEPROP 2 LAST VALUE PICKUP_SMDC20
J 0
(3425 3575);
DISPLAY 0.808511 (3425 3575);
FORCEPROP 1 LAST MATERIAL EMPTY
J 0
(3406 3407);
DISPLAY 0.723404 (3406 3407);
PAINT GREEN (3406 3407);
FORCEPROP 1 LAST $LOCATION ME2
J 0
(3406 3536);
DISPLAY 0.723404 (3406 3536);
PAINT GREEN (3406 3536);
FORCEPROP 1 LAST PATH I10
J 0
(3800 3150);
DISPLAY 0.723404 (3800 3150);
PAINT GREEN (3800 3150);
DISPLAY INVISIBLE (3800 3150);
FORCEPROP 1 LAST PIN_NAMES_ROTATE True
J 0
(3600 3275);
DISPLAY 0.489362 (3600 3275);
PAINT GREEN (3600 3275);
DISPLAY INVISIBLE (3600 3275);
FORCEPROP 1 LAST PIN_TEXT_VISIBLE True
J 0
(3600 3275);
DISPLAY 0.489362 (3600 3275);
PAINT GREEN (3600 3275);
DISPLAY INVISIBLE (3600 3275);
FORCEPROP 1 LAST NEEDS_NO_SIZE TRUE
J 0
(3800 3207);
DISPLAY 0.723404 (3800 3207);
PAINT GREEN (3800 3207);
DISPLAY INVISIBLE (3800 3207);
FORCEPROP 1 LAST CDS_LMAN_SYM_OUTLINE -200,125,200,-125
J 0
(3600 3275);
DISPLAY 0.468085 (3600 3275);
PAINT GREEN (3600 3275);
DISPLAY INVISIBLE (3600 3275);
FORCEPROP 2 LAST CDS_LIB pure_quanta
J 0
(3600 3275);
PAINT MONO (3600 3275);
DISPLAY INVISIBLE (3600 3275);
FORCEPROP 1 LAST $LOCATION ME2
J 0
(3425 3675);
DISPLAY 1.021277 (3425 3675);
DISPLAY INVISIBLE (3425 3675);
FORCEPROP 2 LAST CDS_LOCATION ME2
J 0
(3425 3675);
DISPLAY 1.021277 (3425 3675);
DISPLAY INVISIBLE (3425 3675);
FORCEADD ME_DUMMY_SYMBOL..1
(3600 2700);
FORCEPROP 1 LAST PART_NUMBER DUMMY48
J 0
(3406 2897);
DISPLAY 0.723404 (3406 2897);
PAINT GREEN (3406 2897);
DISPLAY INVISIBLE (3406 2897);
FORCEPROP 1 LAST MATERIAL EMPTY
J 0
(3406 2832);
DISPLAY 0.723404 (3406 2832);
PAINT GREEN (3406 2832);
FORCEPROP 2 LAST PART_TYPE MECH
J 0
(3425 3050);
DISPLAY 0.808511 (3425 3050);
FORCEPROP 2 LAST VALUE PICKUP_SMDC20
J 0
(3425 3000);
DISPLAY 0.808511 (3425 3000);
FORCEPROP 1 LAST $LOCATION ME3
J 0
(3406 2961);
DISPLAY 0.723404 (3406 2961);
PAINT GREEN (3406 2961);
FORCEPROP 1 LAST PATH I11
J 0
(3800 2575);
DISPLAY 0.723404 (3800 2575);
PAINT GREEN (3800 2575);
DISPLAY INVISIBLE (3800 2575);
FORCEPROP 1 LAST PIN_NAMES_ROTATE True
J 0
(3600 2700);
DISPLAY 0.489362 (3600 2700);
PAINT GREEN (3600 2700);
DISPLAY INVISIBLE (3600 2700);
FORCEPROP 1 LAST PIN_TEXT_VISIBLE True
J 0
(3600 2700);
DISPLAY 0.489362 (3600 2700);
PAINT GREEN (3600 2700);
DISPLAY INVISIBLE (3600 2700);
FORCEPROP 1 LAST NEEDS_NO_SIZE TRUE
J 0
(3800 2632);
DISPLAY 0.723404 (3800 2632);
PAINT GREEN (3800 2632);
DISPLAY INVISIBLE (3800 2632);
FORCEPROP 1 LAST CDS_LMAN_SYM_OUTLINE -200,125,200,-125
J 0
(3600 2700);
DISPLAY 0.468085 (3600 2700);
PAINT GREEN (3600 2700);
DISPLAY INVISIBLE (3600 2700);
FORCEPROP 2 LAST CDS_LIB pure_quanta
J 0
(3600 2700);
PAINT MONO (3600 2700);
DISPLAY INVISIBLE (3600 2700);
FORCEPROP 1 LAST $LOCATION ME3
J 0
(3425 3100);
DISPLAY 1.021277 (3425 3100);
DISPLAY INVISIBLE (3425 3100);
FORCEPROP 2 LAST CDS_LOCATION ME3
J 0
(3425 3100);
DISPLAY 1.021277 (3425 3100);
DISPLAY INVISIBLE (3425 3100);
FORCEADD ME_DUMMY_SYMBOL..1
(4245 1955);
FORCEPROP 1 LAST PART_NUMBER DUMMY48
J 0
(4051 2152);
DISPLAY 0.723404 (4051 2152);
PAINT GREEN (4051 2152);
DISPLAY INVISIBLE (4051 2152);
FORCEPROP 2 LAST PART_TYPE MECH
J 0
(4055 2335);
DISPLAY 0.808511 (4055 2335);
FORCEPROP 1 LAST MATERIAL EMPTY
J 0
(4051 2087);
DISPLAY 0.723404 (4051 2087);
PAINT GREEN (4051 2087);
FORCEPROP 2 LAST VALUE PICKUP_SMDC20
J 0
(4055 2285);
DISPLAY 0.808511 (4055 2285);
FORCEPROP 1 LAST $LOCATION ME15
J 0
(4051 2216);
DISPLAY 0.723404 (4051 2216);
PAINT GREEN (4051 2216);
FORCEPROP 1 LAST PATH I12
J 0
(4445 1830);
DISPLAY 0.723404 (4445 1830);
PAINT GREEN (4445 1830);
DISPLAY INVISIBLE (4445 1830);
FORCEPROP 1 LAST PIN_NAMES_ROTATE True
J 0
(4245 1955);
DISPLAY 0.489362 (4245 1955);
PAINT GREEN (4245 1955);
DISPLAY INVISIBLE (4245 1955);
FORCEPROP 1 LAST PIN_TEXT_VISIBLE True
J 0
(4245 1955);
DISPLAY 0.489362 (4245 1955);
PAINT GREEN (4245 1955);
DISPLAY INVISIBLE (4245 1955);
FORCEPROP 1 LAST NEEDS_NO_SIZE TRUE
J 0
(4445 1887);
DISPLAY 0.723404 (4445 1887);
PAINT GREEN (4445 1887);
DISPLAY INVISIBLE (4445 1887);
FORCEPROP 1 LAST CDS_LMAN_SYM_OUTLINE -200,125,200,-125
J 0
(4245 1955);
DISPLAY 0.468085 (4245 1955);
PAINT GREEN (4245 1955);
DISPLAY INVISIBLE (4245 1955);
FORCEPROP 2 LAST CDS_LIB pure_quanta
J 0
(4245 1955);
DISPLAY INVISIBLE (4245 1955);
FORCEPROP 0 LAST CDS_LOCATION ME15
J 0
(4055 2375);
DISPLAY 1.021277 (4055 2375);
DISPLAY INVISIBLE (4055 2375);
FORCEADD ME_DUMMY_SYMBOL..1
(3605 1960);
FORCEPROP 1 LAST PART_NUMBER DUMMY48
J 0
(3411 2157);
DISPLAY 0.723404 (3411 2157);
PAINT GREEN (3411 2157);
DISPLAY INVISIBLE (3411 2157);
FORCEPROP 2 LAST PART_TYPE MECH
J 0
(3415 2340);
DISPLAY 0.808511 (3415 2340);
FORCEPROP 1 LAST MATERIAL EMPTY
J 0
(3411 2092);
DISPLAY 0.723404 (3411 2092);
PAINT GREEN (3411 2092);
FORCEPROP 2 LAST VALUE PICKUP_SMDC20
J 0
(3415 2290);
DISPLAY 0.808511 (3415 2290);
FORCEPROP 1 LAST $LOCATION ME13
J 0
(3411 2221);
DISPLAY 0.723404 (3411 2221);
PAINT GREEN (3411 2221);
FORCEPROP 1 LAST PATH I13
J 0
(3805 1835);
DISPLAY 0.723404 (3805 1835);
PAINT GREEN (3805 1835);
DISPLAY INVISIBLE (3805 1835);
FORCEPROP 1 LAST PIN_NAMES_ROTATE True
J 0
(3605 1960);
DISPLAY 0.489362 (3605 1960);
PAINT GREEN (3605 1960);
DISPLAY INVISIBLE (3605 1960);
FORCEPROP 1 LAST PIN_TEXT_VISIBLE True
J 0
(3605 1960);
DISPLAY 0.489362 (3605 1960);
PAINT GREEN (3605 1960);
DISPLAY INVISIBLE (3605 1960);
FORCEPROP 1 LAST NEEDS_NO_SIZE TRUE
J 0
(3805 1892);
DISPLAY 0.723404 (3805 1892);
PAINT GREEN (3805 1892);
DISPLAY INVISIBLE (3805 1892);
FORCEPROP 1 LAST CDS_LMAN_SYM_OUTLINE -200,125,200,-125
J 0
(3605 1960);
DISPLAY 0.468085 (3605 1960);
PAINT GREEN (3605 1960);
DISPLAY INVISIBLE (3605 1960);
FORCEPROP 2 LAST CDS_LIB pure_quanta
J 0
(3605 1960);
DISPLAY INVISIBLE (3605 1960);
FORCEPROP 0 LAST CDS_LOCATION ME13
J 0
(3415 2380);
DISPLAY 1.021277 (3415 2380);
DISPLAY INVISIBLE (3415 2380);
FORCEADD ME_DUMMY_SYMBOL..1
(5615 3270);
FORCEPROP 1 LAST PART_NUMBER DUMMY48
J 0
(5421 3467);
DISPLAY 0.723404 (5421 3467);
PAINT GREEN (5421 3467);
DISPLAY INVISIBLE (5421 3467);
FORCEPROP 2 LAST PART_TYPE MECH
J 0
(5425 3650);
DISPLAY 0.808511 (5425 3650);
FORCEPROP 1 LAST MATERIAL EMPTY
J 0
(5421 3402);
DISPLAY 0.723404 (5421 3402);
PAINT GREEN (5421 3402);
FORCEPROP 2 LAST VALUE PICKUP_SMDC20
J 0
(5425 3600);
DISPLAY 0.808511 (5425 3600);
FORCEPROP 1 LAST $LOCATION ME11
J 0
(5421 3531);
DISPLAY 0.723404 (5421 3531);
PAINT GREEN (5421 3531);
FORCEPROP 1 LAST PATH I14
J 0
(5815 3145);
DISPLAY 0.723404 (5815 3145);
PAINT GREEN (5815 3145);
DISPLAY INVISIBLE (5815 3145);
FORCEPROP 1 LAST PIN_NAMES_ROTATE True
J 0
(5615 3270);
DISPLAY 0.489362 (5615 3270);
PAINT GREEN (5615 3270);
DISPLAY INVISIBLE (5615 3270);
FORCEPROP 1 LAST PIN_TEXT_VISIBLE True
J 0
(5615 3270);
DISPLAY 0.489362 (5615 3270);
PAINT GREEN (5615 3270);
DISPLAY INVISIBLE (5615 3270);
FORCEPROP 1 LAST NEEDS_NO_SIZE TRUE
J 0
(5815 3202);
DISPLAY 0.723404 (5815 3202);
PAINT GREEN (5815 3202);
DISPLAY INVISIBLE (5815 3202);
FORCEPROP 2 LAST CDS_LIB pure_quanta
J 0
(5615 3270);
DISPLAY INVISIBLE (5615 3270);
FORCEPROP 1 LAST CDS_LMAN_SYM_OUTLINE -200,125,200,-125
J 0
(5615 3270);
DISPLAY 0.468085 (5615 3270);
PAINT GREEN (5615 3270);
DISPLAY INVISIBLE (5615 3270);
FORCEPROP 0 LAST CDS_LOCATION ME11
J 0
(5425 3690);
DISPLAY 1.021277 (5425 3690);
DISPLAY INVISIBLE (5425 3690);
FORCEADD ME_DUMMY_SYMBOL..1
(5620 2640);
FORCEPROP 1 LAST PART_NUMBER DUMMY48
J 0
(5426 2837);
DISPLAY 0.723404 (5426 2837);
PAINT GREEN (5426 2837);
DISPLAY INVISIBLE (5426 2837);
FORCEPROP 1 LAST MATERIAL EMPTY
J 0
(5426 2772);
DISPLAY 0.723404 (5426 2772);
PAINT GREEN (5426 2772);
FORCEPROP 2 LAST VALUE PICKUP_SMDC20
J 0
(5430 2970);
DISPLAY 0.808511 (5430 2970);
FORCEPROP 2 LAST PART_TYPE MECH
J 0
(5430 3020);
DISPLAY 0.808511 (5430 3020);
FORCEPROP 1 LAST $LOCATION ME12
J 0
(5426 2901);
DISPLAY 0.723404 (5426 2901);
PAINT GREEN (5426 2901);
FORCEPROP 1 LAST PATH I15
J 0
(5820 2515);
DISPLAY 0.723404 (5820 2515);
PAINT GREEN (5820 2515);
DISPLAY INVISIBLE (5820 2515);
FORCEPROP 1 LAST NEEDS_NO_SIZE TRUE
J 0
(5820 2572);
DISPLAY 0.723404 (5820 2572);
PAINT GREEN (5820 2572);
DISPLAY INVISIBLE (5820 2572);
FORCEPROP 1 LAST PIN_TEXT_VISIBLE True
J 0
(5620 2640);
DISPLAY 0.489362 (5620 2640);
PAINT GREEN (5620 2640);
DISPLAY INVISIBLE (5620 2640);
FORCEPROP 1 LAST PIN_NAMES_ROTATE True
J 0
(5620 2640);
DISPLAY 0.489362 (5620 2640);
PAINT GREEN (5620 2640);
DISPLAY INVISIBLE (5620 2640);
FORCEPROP 2 LAST CDS_LIB pure_quanta
J 0
(5620 2640);
DISPLAY INVISIBLE (5620 2640);
FORCEPROP 1 LAST CDS_LMAN_SYM_OUTLINE -200,125,200,-125
J 0
(5620 2640);
DISPLAY 0.468085 (5620 2640);
PAINT GREEN (5620 2640);
DISPLAY INVISIBLE (5620 2640);
FORCEPROP 0 LAST CDS_LOCATION ME12
J 0
(5430 3060);
DISPLAY 1.021277 (5430 3060);
DISPLAY INVISIBLE (5430 3060);
FORCEADD ME_DUMMY_SYMBOL..1
(3610 1330);
FORCEPROP 1 LAST PART_NUMBER DUMMY48
J 0
(3416 1527);
DISPLAY 0.723404 (3416 1527);
PAINT GREEN (3416 1527);
DISPLAY INVISIBLE (3416 1527);
FORCEPROP 1 LAST MATERIAL EMPTY
J 0
(3416 1462);
DISPLAY 0.723404 (3416 1462);
PAINT GREEN (3416 1462);
FORCEPROP 2 LAST PART_TYPE MECH
J 0
(3420 1710);
DISPLAY 0.808511 (3420 1710);
FORCEPROP 2 LAST VALUE PICKUP_SMDC20
J 0
(3420 1660);
DISPLAY 0.808511 (3420 1660);
FORCEPROP 1 LAST $LOCATION ME14
J 0
(3416 1591);
DISPLAY 0.723404 (3416 1591);
PAINT GREEN (3416 1591);
FORCEPROP 1 LAST PATH I16
J 0
(3810 1205);
DISPLAY 0.723404 (3810 1205);
PAINT GREEN (3810 1205);
DISPLAY INVISIBLE (3810 1205);
FORCEPROP 1 LAST NEEDS_NO_SIZE TRUE
J 0
(3810 1262);
DISPLAY 0.723404 (3810 1262);
PAINT GREEN (3810 1262);
DISPLAY INVISIBLE (3810 1262);
FORCEPROP 1 LAST PIN_TEXT_VISIBLE True
J 0
(3610 1330);
DISPLAY 0.489362 (3610 1330);
PAINT GREEN (3610 1330);
DISPLAY INVISIBLE (3610 1330);
FORCEPROP 1 LAST PIN_NAMES_ROTATE True
J 0
(3610 1330);
DISPLAY 0.489362 (3610 1330);
PAINT GREEN (3610 1330);
DISPLAY INVISIBLE (3610 1330);
FORCEPROP 1 LAST CDS_LMAN_SYM_OUTLINE -200,125,200,-125
J 0
(3610 1330);
DISPLAY 0.468085 (3610 1330);
PAINT GREEN (3610 1330);
DISPLAY INVISIBLE (3610 1330);
FORCEPROP 2 LAST CDS_LIB pure_quanta
J 0
(3610 1330);
DISPLAY INVISIBLE (3610 1330);
FORCEPROP 0 LAST CDS_LOCATION ME14
J 0
(3420 1750);
DISPLAY 1.021277 (3420 1750);
DISPLAY INVISIBLE (3420 1750);
FORCEADD DUMMY_SYMBOL..1
(2275 3125);
FORCEPROP 1 LAST PART_NUMBER DUMMY12
J 0
(2079 3302);
DISPLAY 0.723404 (2079 3302);
PAINT GREEN (2079 3302);
DISPLAY INVISIBLE (2079 3302);
FORCEPROP 2 LAST VALUE BATTERY_SYMBOL
J 0
(2100 3450);
DISPLAY 0.680851 (2100 3450);
FORCEPROP 0 LAST L1 AHL03003003
J 0
(2100 3600);
DISPLAY 0.680851 (2100 3600);
FORCEPROP 1 LAST MATERIAL MECH
J 0
(2079 3216);
DISPLAY 0.723404 (2079 3216);
PAINT GREEN (2079 3216);
FORCEPROP 2 LAST PART_TYPE MECH
J 0
(2100 3500);
DISPLAY 0.680851 (2100 3500);
FORCEPROP 1 LAST $LOCATION DM13
J 0
(2079 3395);
DISPLAY 0.723404 (2079 3395);
PAINT GREEN (2079 3395);
FORCEPROP 2 LASTPIN (2475 3150) $PN 1
R 1
J 0
(2465 3160);
DISPLAY 0.808511 (2465 3160);
FORCEPROP 1 LAST PATH I17
J 0
(2475 3050);
DISPLAY 0.723404 (2475 3050);
DISPLAY INVISIBLE (2475 3050);
FORCEPROP 1 LAST PIN_NAMES_ROTATE True
J 0
(2275 3125);
DISPLAY 0.489362 (2275 3125);
PAINT GREEN (2275 3125);
DISPLAY INVISIBLE (2275 3125);
FORCEPROP 1 LAST CDS_LMAN_SYM_OUTLINE -200,75,200,-75
J 0
(2275 3125);
DISPLAY 0.468085 (2275 3125);
PAINT GREEN (2275 3125);
DISPLAY INVISIBLE (2275 3125);
FORCEPROP 2 LAST CDS_LIB pure_quanta
J 0
(2275 3125);
PAINT MONO (2275 3125);
DISPLAY INVISIBLE (2275 3125);
FORCEPROP 2 LAST CDS_LOCATION DM13
J 0
(2100 3650);
DISPLAY 1.021277 (2100 3650);
DISPLAY INVISIBLE (2100 3650);
FORCEPROP 2 LAST $SEC 1
J 0
(2100 3650);
DISPLAY 0.680851 (2100 3650);
PAINT MONO (2100 3650);
DISPLAY INVISIBLE (2100 3650);
FORCEPROP 2 LAST CDS_SEC 1
J 0
(2100 3650);
DISPLAY 1.021277 (2100 3650);
DISPLAY INVISIBLE (2100 3650);
FORCEADD ME_DUMMY_SYMBOL..1
(4975 3275);
FORCEPROP 1 LAST PART_NUMBER DUMMY48
J 0
(4781 3472);
DISPLAY 0.723404 (4781 3472);
PAINT GREEN (4781 3472);
DISPLAY INVISIBLE (4781 3472);
FORCEPROP 1 LAST MATERIAL EMPTY
J 0
(4781 3407);
DISPLAY 0.723404 (4781 3407);
PAINT GREEN (4781 3407);
FORCEPROP 2 LAST PART_TYPE MECH
J 0
(4785 3655);
DISPLAY 0.808511 (4785 3655);
FORCEPROP 2 LAST VALUE PICKUP_SMDC20
J 0
(4785 3605);
DISPLAY 0.808511 (4785 3605);
FORCEPROP 1 LAST $LOCATION ME9
J 0
(4781 3536);
DISPLAY 0.723404 (4781 3536);
PAINT GREEN (4781 3536);
FORCEPROP 1 LAST PATH I18
J 0
(5175 3150);
DISPLAY 0.723404 (5175 3150);
PAINT GREEN (5175 3150);
DISPLAY INVISIBLE (5175 3150);
FORCEPROP 1 LAST PIN_NAMES_ROTATE True
J 0
(4975 3275);
DISPLAY 0.489362 (4975 3275);
PAINT GREEN (4975 3275);
DISPLAY INVISIBLE (4975 3275);
FORCEPROP 1 LAST PIN_TEXT_VISIBLE True
J 0
(4975 3275);
DISPLAY 0.489362 (4975 3275);
PAINT GREEN (4975 3275);
DISPLAY INVISIBLE (4975 3275);
FORCEPROP 1 LAST NEEDS_NO_SIZE TRUE
J 0
(5175 3207);
DISPLAY 0.723404 (5175 3207);
PAINT GREEN (5175 3207);
DISPLAY INVISIBLE (5175 3207);
FORCEPROP 2 LAST CDS_LIB pure_quanta
J 0
(4975 3275);
DISPLAY INVISIBLE (4975 3275);
FORCEPROP 1 LAST CDS_LMAN_SYM_OUTLINE -200,125,200,-125
J 0
(4975 3275);
DISPLAY 0.468085 (4975 3275);
PAINT GREEN (4975 3275);
DISPLAY INVISIBLE (4975 3275);
FORCEPROP 0 LAST CDS_LOCATION ME9
J 0
(4785 3695);
DISPLAY 1.021277 (4785 3695);
DISPLAY INVISIBLE (4785 3695);
FORCEADD ME_DUMMY_SYMBOL..1
(4980 2645);
FORCEPROP 1 LAST PART_NUMBER DUMMY48
J 0
(4786 2842);
DISPLAY 0.723404 (4786 2842);
PAINT GREEN (4786 2842);
DISPLAY INVISIBLE (4786 2842);
FORCEPROP 1 LAST MATERIAL EMPTY
J 0
(4786 2777);
DISPLAY 0.723404 (4786 2777);
PAINT GREEN (4786 2777);
FORCEPROP 2 LAST PART_TYPE MECH
J 0
(4790 3025);
DISPLAY 0.808511 (4790 3025);
FORCEPROP 2 LAST VALUE PICKUP_SMDC20
J 0
(4790 2975);
DISPLAY 0.808511 (4790 2975);
FORCEPROP 1 LAST $LOCATION ME10
J 0
(4786 2906);
DISPLAY 0.723404 (4786 2906);
PAINT GREEN (4786 2906);
FORCEPROP 1 LAST PATH I19
J 0
(5180 2520);
DISPLAY 0.723404 (5180 2520);
PAINT GREEN (5180 2520);
DISPLAY INVISIBLE (5180 2520);
FORCEPROP 1 LAST NEEDS_NO_SIZE TRUE
J 0
(5180 2577);
DISPLAY 0.723404 (5180 2577);
PAINT GREEN (5180 2577);
DISPLAY INVISIBLE (5180 2577);
FORCEPROP 1 LAST PIN_TEXT_VISIBLE True
J 0
(4980 2645);
DISPLAY 0.489362 (4980 2645);
PAINT GREEN (4980 2645);
DISPLAY INVISIBLE (4980 2645);
FORCEPROP 1 LAST PIN_NAMES_ROTATE True
J 0
(4980 2645);
DISPLAY 0.489362 (4980 2645);
PAINT GREEN (4980 2645);
DISPLAY INVISIBLE (4980 2645);
FORCEPROP 1 LAST CDS_LMAN_SYM_OUTLINE -200,125,200,-125
J 0
(4980 2645);
DISPLAY 0.468085 (4980 2645);
PAINT GREEN (4980 2645);
DISPLAY INVISIBLE (4980 2645);
FORCEPROP 2 LAST CDS_LIB pure_quanta
J 0
(4980 2645);
DISPLAY INVISIBLE (4980 2645);
FORCEPROP 0 LAST CDS_LOCATION ME10
J 0
(4790 3065);
DISPLAY 1.021277 (4790 3065);
DISPLAY INVISIBLE (4790 3065);
FORCEADD DUMMY_SYMBOL..1
(-132 3078);
FORCEPROP 1 LAST PART_NUMBER DUMMY10
J 0
(-328 3255);
DISPLAY 0.723404 (-328 3255);
PAINT GREEN (-328 3255);
DISPLAY INVISIBLE (-328 3255);
FORCEPROP 1 LAST MATERIAL MECH
J 0
(-328 3169);
DISPLAY 0.723404 (-328 3169);
PAINT GREEN (-328 3169);
FORCEPROP 2 LAST PART_TYPE MECH
J 0
(-328 3414);
DISPLAY 0.680851 (-328 3414);
FORCEPROP 2 LAST VALUE MECHANIC_SYMBOL
J 0
(-328 3382);
DISPLAY 0.680851 (-328 3382);
FORCEPROP 1 LAST $LOCATION DM9
J 0
(-328 3348);
DISPLAY 0.723404 (-328 3348);
PAINT GREEN (-328 3348);
FORCEPROP 2 LASTPIN (68 3103) $PN 1
R 1
J 0
(58 3113);
DISPLAY 0.808511 (58 3113);
FORCEPROP 1 LAST PATH I23
J 0
(68 3003);
DISPLAY 0.723404 (68 3003);
DISPLAY INVISIBLE (68 3003);
FORCEPROP 1 LAST PIN_NAMES_ROTATE True
J 0
(-132 3078);
DISPLAY 0.489362 (-132 3078);
PAINT GREEN (-132 3078);
DISPLAY INVISIBLE (-132 3078);
FORCEPROP 1 LAST CDS_LMAN_SYM_OUTLINE -200,75,200,-75
J 0
(-132 3078);
DISPLAY 0.468085 (-132 3078);
PAINT GREEN (-132 3078);
DISPLAY INVISIBLE (-132 3078);
FORCEPROP 2 LAST CDS_LIB pure_quanta
J 0
(-132 3078);
PAINT MONO (-132 3078);
DISPLAY INVISIBLE (-132 3078);
FORCEPROP 2 LAST CDS_LOCATION DM9
J 0
(-325 3450);
DISPLAY 1.021277 (-325 3450);
DISPLAY INVISIBLE (-325 3450);
FORCEPROP 2 LAST $SEC 1
J 0
(-325 3450);
DISPLAY 0.680851 (-325 3450);
PAINT MONO (-325 3450);
DISPLAY INVISIBLE (-325 3450);
FORCEPROP 2 LAST CDS_SEC 1
J 0
(-325 3450);
DISPLAY 1.021277 (-325 3450);
DISPLAY INVISIBLE (-325 3450);
FORCEADD TP..1
(-500 800);
FORCEPROP 1 LAST PART_NUMBER TP12_BOM
J 1
(-445 755);
DISPLAY 0.446809 (-445 755);
PAINT GREEN (-445 755);
DISPLAY INVISIBLE (-445 755);
FORCEPROP 1 LAST MATERIAL NA
J 0
(-475 725);
DISPLAY 0.446809 (-475 725);
FORCEPROP 1 LAST LOCATION U1_BL
J 1
(-495 820);
DISPLAY 0.446809 (-495 820);
PAINT PINK (-495 820);
FORCEPROP 0 LASTPIN (-500 750) $PN 1
R 1
J 2
(-510 740);
DISPLAY 0.680851 (-510 740);
PAINT MONO (-510 740);
FORCEPROP 0 LAST QPN DGRA^000178
J 0
(-500 650);
DISPLAY 0.808511 (-500 650);
FORCEPROP 1 LAST PATH I40
J 1
(-495 845);
DISPLAY 0.446809 (-495 845);
PAINT GREEN (-495 845);
DISPLAY INVISIBLE (-495 845);
FORCEPROP 1 LASTPIN (-500 750) $PIN_NUMBER ?
J 2
(-450 750);
DISPLAY 0.702128 (-450 750);
PAINT MONO (-450 750);
DISPLAY INVISIBLE (-450 750);
FORCEPROP 2 LAST CDS_LIB pure_quanta
J 0
(-500 800);
DISPLAY INVISIBLE (-500 800);
FORCEPROP 1 LAST PACK_TYPE TP_BOM ONLY
J 1
(-445 735);
DISPLAY 0.446809 (-445 735);
PAINT GREEN (-445 735);
DISPLAY INVISIBLE (-445 735);
FORCEPROP 0 LAST $SEC 1
J 0
(-475 850);
DISPLAY 0.680851 (-475 850);
PAINT MONO (-475 850);
DISPLAY INVISIBLE (-475 850);
FORCEPROP 0 LAST CDS_SEC 1
J 0
(-475 850);
DISPLAY 1.021277 (-475 850);
DISPLAY INVISIBLE (-475 850);
FORCEADD TP..1
(50 800);
FORCEPROP 1 LAST PART_NUMBER TP12_BOM
J 1
(105 755);
DISPLAY 0.446809 (105 755);
PAINT GREEN (105 755);
DISPLAY INVISIBLE (105 755);
FORCEPROP 0 LAST QPN DGRA^000178
J 0
(50 650);
DISPLAY 0.808511 (50 650);
FORCEPROP 1 LAST MATERIAL NA
J 0
(75 725);
DISPLAY 0.446809 (75 725);
FORCEPROP 1 LAST LOCATION U2_BL
J 1
(55 820);
DISPLAY 0.446809 (55 820);
PAINT PINK (55 820);
FORCEPROP 0 LASTPIN (50 750) $PN 1
R 1
J 2
(40 740);
DISPLAY 0.680851 (40 740);
PAINT MONO (40 740);
FORCEPROP 1 LAST PATH I41
J 1
(55 845);
DISPLAY 0.446809 (55 845);
PAINT GREEN (55 845);
DISPLAY INVISIBLE (55 845);
FORCEPROP 1 LASTPIN (50 750) $PIN_NUMBER ?
J 2
(100 750);
DISPLAY 0.702128 (100 750);
PAINT MONO (100 750);
DISPLAY INVISIBLE (100 750);
FORCEPROP 2 LAST CDS_LIB pure_quanta
J 0
(50 800);
DISPLAY INVISIBLE (50 800);
FORCEPROP 1 LAST PACK_TYPE TP_BOM ONLY
J 1
(105 735);
DISPLAY 0.446809 (105 735);
PAINT GREEN (105 735);
DISPLAY INVISIBLE (105 735);
FORCEPROP 0 LAST $SEC 1
J 0
(75 850);
DISPLAY 0.680851 (75 850);
PAINT MONO (75 850);
DISPLAY INVISIBLE (75 850);
FORCEPROP 0 LAST CDS_SEC 1
J 0
(75 850);
DISPLAY 1.021277 (75 850);
DISPLAY INVISIBLE (75 850);
FORCEADD TP..1
(50 250);
FORCEPROP 1 LAST PART_NUMBER TP12_BOM
J 1
(105 205);
DISPLAY 0.446809 (105 205);
PAINT GREEN (105 205);
DISPLAY INVISIBLE (105 205);
FORCEPROP 0 LASTPIN (50 200) $PN 1
R 1
J 2
(40 190);
DISPLAY 0.680851 (40 190);
PAINT MONO (40 190);
FORCEPROP 0 LAST QPN DGRA^000128
J 0
(50 100);
DISPLAY 0.808511 (50 100);
FORCEPROP 1 LAST MATERIAL NA
J 0
(75 175);
DISPLAY 0.446809 (75 175);
FORCEPROP 1 LAST LOCATION U2_BP
J 1
(55 270);
DISPLAY 0.446809 (55 270);
PAINT PINK (55 270);
FORCEPROP 1 LAST PATH I42
J 1
(55 295);
DISPLAY 0.446809 (55 295);
PAINT GREEN (55 295);
DISPLAY INVISIBLE (55 295);
FORCEPROP 1 LASTPIN (50 200) $PIN_NUMBER ?
J 2
(100 200);
DISPLAY 0.702128 (100 200);
PAINT MONO (100 200);
DISPLAY INVISIBLE (100 200);
FORCEPROP 2 LAST CDS_LIB pure_quanta
J 0
(50 250);
DISPLAY INVISIBLE (50 250);
FORCEPROP 1 LAST PACK_TYPE TP_BOM ONLY
J 1
(105 185);
DISPLAY 0.446809 (105 185);
PAINT GREEN (105 185);
DISPLAY INVISIBLE (105 185);
FORCEPROP 0 LAST $SEC 1
J 0
(75 300);
DISPLAY 0.680851 (75 300);
PAINT MONO (75 300);
DISPLAY INVISIBLE (75 300);
FORCEPROP 0 LAST CDS_SEC 1
J 0
(75 300);
DISPLAY 1.021277 (75 300);
DISPLAY INVISIBLE (75 300);
FORCEADD TP..1
(-500 250);
FORCEPROP 1 LAST PART_NUMBER TP12_BOM
J 1
(-445 205);
DISPLAY 0.446809 (-445 205);
PAINT GREEN (-445 205);
DISPLAY INVISIBLE (-445 205);
FORCEPROP 0 LAST QPN DGRA^000128
J 0
(-500 100);
DISPLAY 0.808511 (-500 100);
FORCEPROP 1 LAST MATERIAL NA
J 0
(-475 175);
DISPLAY 0.446809 (-475 175);
FORCEPROP 1 LAST LOCATION U1_BP
J 1
(-495 270);
DISPLAY 0.446809 (-495 270);
PAINT PINK (-495 270);
FORCEPROP 0 LASTPIN (-500 200) $PN 1
R 1
J 2
(-510 190);
DISPLAY 0.680851 (-510 190);
PAINT MONO (-510 190);
FORCEPROP 1 LAST PATH I43
J 1
(-495 295);
DISPLAY 0.446809 (-495 295);
PAINT GREEN (-495 295);
DISPLAY INVISIBLE (-495 295);
FORCEPROP 1 LASTPIN (-500 200) $PIN_NUMBER ?
J 2
(-450 200);
DISPLAY 0.702128 (-450 200);
PAINT MONO (-450 200);
DISPLAY INVISIBLE (-450 200);
FORCEPROP 2 LAST CDS_LIB pure_quanta
J 0
(-500 250);
DISPLAY INVISIBLE (-500 250);
FORCEPROP 1 LAST PACK_TYPE TP_BOM ONLY
J 1
(-445 185);
DISPLAY 0.446809 (-445 185);
PAINT GREEN (-445 185);
DISPLAY INVISIBLE (-445 185);
FORCEPROP 0 LAST $SEC 1
J 0
(-475 300);
DISPLAY 0.680851 (-475 300);
PAINT MONO (-475 300);
DISPLAY INVISIBLE (-475 300);
FORCEPROP 0 LAST CDS_SEC 1
J 0
(-475 300);
DISPLAY 1.021277 (-475 300);
DISPLAY INVISIBLE (-475 300);
FORCEADD TP..1
(1375 250);
FORCEPROP 1 LAST PART_NUMBER TP12_BOM
J 1
(1430 205);
DISPLAY 0.446809 (1430 205);
PAINT GREEN (1430 205);
DISPLAY INVISIBLE (1430 205);
FORCEPROP 1 LAST MATERIAL NA
J 0
(1400 175);
DISPLAY 0.446809 (1400 175);
FORCEPROP 0 LAST QPN DGRA^000180
J 0
(1375 100);
DISPLAY 0.638298 (1375 100);
FORCEPROP 1 LAST LOCATION U2_DC
J 1
(1380 270);
DISPLAY 0.446809 (1380 270);
PAINT PINK (1380 270);
FORCEPROP 0 LASTPIN (1375 200) $PN 1
R 1
J 2
(1365 190);
DISPLAY 0.680851 (1365 190);
PAINT MONO (1365 190);
FORCEPROP 1 LAST PATH I45
J 1
(1380 295);
DISPLAY 0.446809 (1380 295);
PAINT GREEN (1380 295);
DISPLAY INVISIBLE (1380 295);
FORCEPROP 1 LASTPIN (1375 200) $PIN_NUMBER ?
J 2
(1425 200);
DISPLAY 0.702128 (1425 200);
PAINT MONO (1425 200);
DISPLAY INVISIBLE (1425 200);
FORCEPROP 2 LAST CDS_LIB pure_quanta
J 0
(1375 250);
DISPLAY INVISIBLE (1375 250);
FORCEPROP 1 LAST PACK_TYPE TP_BOM ONLY
J 1
(1430 185);
DISPLAY 0.446809 (1430 185);
PAINT GREEN (1430 185);
DISPLAY INVISIBLE (1430 185);
FORCEPROP 0 LAST $SEC 1
J 0
(1400 300);
DISPLAY 0.680851 (1400 300);
PAINT MONO (1400 300);
DISPLAY INVISIBLE (1400 300);
FORCEPROP 0 LAST CDS_SEC 1
J 0
(1400 300);
DISPLAY 1.021277 (1400 300);
DISPLAY INVISIBLE (1400 300);
FORCEADD TP..1
(825 250);
FORCEPROP 1 LAST PART_NUMBER TP12_BOM
J 1
(880 205);
DISPLAY 0.446809 (880 205);
PAINT GREEN (880 205);
DISPLAY INVISIBLE (880 205);
FORCEPROP 1 LAST MATERIAL NA
J 0
(850 175);
DISPLAY 0.446809 (850 175);
FORCEPROP 0 LAST QPN DGRA^000180
J 0
(825 100);
DISPLAY 0.638298 (825 100);
FORCEPROP 1 LAST LOCATION U1_DC
J 1
(830 270);
DISPLAY 0.446809 (830 270);
PAINT PINK (830 270);
FORCEPROP 0 LASTPIN (825 200) $PN 1
R 1
J 2
(815 190);
DISPLAY 0.680851 (815 190);
PAINT MONO (815 190);
FORCEPROP 1 LAST PATH I47
J 1
(830 295);
DISPLAY 0.446809 (830 295);
PAINT GREEN (830 295);
DISPLAY INVISIBLE (830 295);
FORCEPROP 1 LASTPIN (825 200) $PIN_NUMBER ?
J 2
(875 200);
DISPLAY 0.702128 (875 200);
PAINT MONO (875 200);
DISPLAY INVISIBLE (875 200);
FORCEPROP 2 LAST CDS_LIB pure_quanta
J 0
(825 250);
DISPLAY INVISIBLE (825 250);
FORCEPROP 1 LAST PACK_TYPE TP_BOM ONLY
J 1
(880 185);
DISPLAY 0.446809 (880 185);
PAINT GREEN (880 185);
DISPLAY INVISIBLE (880 185);
FORCEPROP 0 LAST $SEC 1
J 0
(850 300);
DISPLAY 0.680851 (850 300);
PAINT MONO (850 300);
DISPLAY INVISIBLE (850 300);
FORCEPROP 0 LAST CDS_SEC 1
J 0
(850 300);
DISPLAY 1.021277 (850 300);
DISPLAY INVISIBLE (850 300);
FORCEADD ME_DUMMY_SYMBOL..1
(-2775 4475);
FORCEPROP 1 LAST PART_NUMBER DUMMY1
J 0
(-2969 4672);
DISPLAY 0.723404 (-2969 4672);
PAINT GREEN (-2969 4672);
DISPLAY INVISIBLE (-2969 4672);
FORCEPROP 2 LAST VALUE QUANTA_LOGO_7X26
J 0
(-2950 4775);
DISPLAY 1.021277 (-2950 4775);
FORCEPROP 2 LAST PART_TYPE MECH
J 0
(-2950 4825);
DISPLAY 1.021277 (-2950 4825);
FORCEPROP 1 LAST MATERIAL EMPTY
J 0
(-2969 4607);
DISPLAY 0.723404 (-2969 4607);
PAINT GREEN (-2969 4607);
FORCEPROP 1 LAST $LOCATION ME17
J 0
(-2969 4736);
DISPLAY 0.723404 (-2969 4736);
PAINT GREEN (-2969 4736);
FORCEPROP 1 LAST PATH I62
J 0
(-2575 4350);
DISPLAY 0.723404 (-2575 4350);
PAINT GREEN (-2575 4350);
DISPLAY INVISIBLE (-2575 4350);
FORCEPROP 1 LAST PIN_NAMES_ROTATE True
J 0
(-2775 4475);
DISPLAY 0.489362 (-2775 4475);
PAINT GREEN (-2775 4475);
DISPLAY INVISIBLE (-2775 4475);
FORCEPROP 1 LAST PIN_TEXT_VISIBLE True
J 0
(-2775 4475);
DISPLAY 0.489362 (-2775 4475);
PAINT GREEN (-2775 4475);
DISPLAY INVISIBLE (-2775 4475);
FORCEPROP 1 LAST NEEDS_NO_SIZE TRUE
J 0
(-2575 4407);
DISPLAY 0.723404 (-2575 4407);
PAINT GREEN (-2575 4407);
DISPLAY INVISIBLE (-2575 4407);
FORCEPROP 1 LAST CDS_LMAN_SYM_OUTLINE -200,125,200,-125
J 0
(-2775 4475);
DISPLAY 0.468085 (-2775 4475);
PAINT GREEN (-2775 4475);
DISPLAY INVISIBLE (-2775 4475);
FORCEPROP 2 LAST CDS_LIB pure_quanta
J 0
(-2775 4475);
DISPLAY INVISIBLE (-2775 4475);
FORCEPROP 0 LAST CDS_LOCATION ME17
J 0
(-2950 4875);
DISPLAY 1.021277 (-2950 4875);
DISPLAY INVISIBLE (-2950 4875);
FORCEADD ME_DUMMY_SYMBOL..1
(-1475 4475);
FORCEPROP 1 LAST PART_NUMBER DUMMY2
J 0
(-1669 4672);
DISPLAY 0.723404 (-1669 4672);
PAINT GREEN (-1669 4672);
DISPLAY INVISIBLE (-1669 4672);
FORCEPROP 1 LAST MATERIAL EMPTY
J 0
(-1669 4607);
DISPLAY 0.723404 (-1669 4607);
PAINT GREEN (-1669 4607);
FORCEPROP 2 LAST PART_TYPE MECH
J 0
(-1650 4825);
DISPLAY 1.021277 (-1650 4825);
FORCEPROP 2 LAST VALUE WEEE
J 0
(-1650 4775);
DISPLAY 1.021277 (-1650 4775);
FORCEPROP 1 LAST $LOCATION ME18
J 0
(-1669 4736);
DISPLAY 0.723404 (-1669 4736);
PAINT GREEN (-1669 4736);
FORCEPROP 1 LAST PATH I63
J 0
(-1275 4350);
DISPLAY 0.723404 (-1275 4350);
PAINT GREEN (-1275 4350);
DISPLAY INVISIBLE (-1275 4350);
FORCEPROP 1 LAST PIN_NAMES_ROTATE True
J 0
(-1475 4475);
DISPLAY 0.489362 (-1475 4475);
PAINT GREEN (-1475 4475);
DISPLAY INVISIBLE (-1475 4475);
FORCEPROP 1 LAST PIN_TEXT_VISIBLE True
J 0
(-1475 4475);
DISPLAY 0.489362 (-1475 4475);
PAINT GREEN (-1475 4475);
DISPLAY INVISIBLE (-1475 4475);
FORCEPROP 1 LAST NEEDS_NO_SIZE TRUE
J 0
(-1275 4407);
DISPLAY 0.723404 (-1275 4407);
PAINT GREEN (-1275 4407);
DISPLAY INVISIBLE (-1275 4407);
FORCEPROP 1 LAST CDS_LMAN_SYM_OUTLINE -200,125,200,-125
J 0
(-1475 4475);
DISPLAY 0.468085 (-1475 4475);
PAINT GREEN (-1475 4475);
DISPLAY INVISIBLE (-1475 4475);
FORCEPROP 2 LAST CDS_LIB pure_quanta
J 0
(-1475 4475);
DISPLAY INVISIBLE (-1475 4475);
FORCEPROP 0 LAST CDS_LOCATION ME18
J 0
(-1650 4875);
DISPLAY 1.021277 (-1650 4875);
DISPLAY INVISIBLE (-1650 4875);
FORCEADD ME_DUMMY_SYMBOL..1
(-50 4500);
FORCEPROP 1 LAST PART_NUMBER DUMMY3
J 0
(-244 4697);
DISPLAY 0.723404 (-244 4697);
PAINT GREEN (-244 4697);
DISPLAY INVISIBLE (-244 4697);
FORCEPROP 1 LAST MATERIAL EMPTY
J 0
(-244 4632);
DISPLAY 0.723404 (-244 4632);
PAINT GREEN (-244 4632);
FORCEPROP 2 LAST PART_TYPE MECH
J 0
(-225 4850);
DISPLAY 1.021277 (-225 4850);
FORCEPROP 2 LAST VALUE PB-E1_SMALL
J 0
(-225 4800);
DISPLAY 1.021277 (-225 4800);
FORCEPROP 1 LAST $LOCATION ME20
J 0
(-244 4761);
DISPLAY 0.723404 (-244 4761);
PAINT GREEN (-244 4761);
FORCEPROP 1 LAST PATH I64
J 0
(150 4375);
DISPLAY 0.723404 (150 4375);
PAINT GREEN (150 4375);
DISPLAY INVISIBLE (150 4375);
FORCEPROP 1 LAST PIN_NAMES_ROTATE True
J 0
(-50 4500);
DISPLAY 0.489362 (-50 4500);
PAINT GREEN (-50 4500);
DISPLAY INVISIBLE (-50 4500);
FORCEPROP 1 LAST PIN_TEXT_VISIBLE True
J 0
(-50 4500);
DISPLAY 0.489362 (-50 4500);
PAINT GREEN (-50 4500);
DISPLAY INVISIBLE (-50 4500);
FORCEPROP 1 LAST NEEDS_NO_SIZE TRUE
J 0
(150 4432);
DISPLAY 0.723404 (150 4432);
PAINT GREEN (150 4432);
DISPLAY INVISIBLE (150 4432);
FORCEPROP 1 LAST CDS_LMAN_SYM_OUTLINE -200,125,200,-125
J 0
(-50 4500);
DISPLAY 0.468085 (-50 4500);
PAINT GREEN (-50 4500);
DISPLAY INVISIBLE (-50 4500);
FORCEPROP 2 LAST CDS_LIB pure_quanta
J 0
(-50 4500);
DISPLAY INVISIBLE (-50 4500);
FORCEPROP 0 LAST CDS_LOCATION ME20
J 0
(-225 4900);
DISPLAY 1.021277 (-225 4900);
DISPLAY INVISIBLE (-225 4900);
FORCEADD ME_DUMMY_SYMBOL..1
(4900 4350);
FORCEPROP 1 LAST PART_NUMBER DUMMY7
J 0
(4706 4547);
DISPLAY 0.723404 (4706 4547);
PAINT GREEN (4706 4547);
DISPLAY INVISIBLE (4706 4547);
FORCEPROP 2 LAST PART_TYPE MECH
J 0
(4725 4700);
DISPLAY 1.021277 (4725 4700);
FORCEPROP 2 LAST VALUE PCB_VENDOR_LOGO_15X8
J 0
(4725 4650);
DISPLAY 0.638298 (4725 4650);
FORCEPROP 1 LAST MATERIAL EMPTY
J 0
(4706 4482);
DISPLAY 0.723404 (4706 4482);
PAINT GREEN (4706 4482);
FORCEPROP 1 LAST $LOCATION ME21
J 0
(4706 4611);
DISPLAY 0.723404 (4706 4611);
PAINT GREEN (4706 4611);
FORCEPROP 1 LAST PATH I65
J 0
(5100 4225);
DISPLAY 0.723404 (5100 4225);
PAINT GREEN (5100 4225);
DISPLAY INVISIBLE (5100 4225);
FORCEPROP 1 LAST CDS_LMAN_SYM_OUTLINE -200,125,200,-125
J 0
(4900 4350);
DISPLAY 0.468085 (4900 4350);
PAINT GREEN (4900 4350);
DISPLAY INVISIBLE (4900 4350);
FORCEPROP 2 LAST CDS_LIB pure_quanta
J 0
(4900 4350);
DISPLAY INVISIBLE (4900 4350);
FORCEPROP 1 LAST PIN_NAMES_ROTATE True
J 0
(4900 4350);
DISPLAY 0.489362 (4900 4350);
PAINT GREEN (4900 4350);
DISPLAY INVISIBLE (4900 4350);
FORCEPROP 1 LAST PIN_TEXT_VISIBLE True
J 0
(4900 4350);
DISPLAY 0.489362 (4900 4350);
PAINT GREEN (4900 4350);
DISPLAY INVISIBLE (4900 4350);
FORCEPROP 1 LAST NEEDS_NO_SIZE TRUE
J 0
(5100 4282);
DISPLAY 0.723404 (5100 4282);
PAINT GREEN (5100 4282);
DISPLAY INVISIBLE (5100 4282);
FORCEPROP 0 LAST CDS_LOCATION ME21
J 0
(4725 4750);
DISPLAY 1.021277 (4725 4750);
DISPLAY INVISIBLE (4725 4750);
FORCEADD TP..1
(-1900 -475);
FORCEPROP 1 LAST PART_NUMBER TP12_BOM
J 1
(-1845 -520);
DISPLAY 0.446809 (-1845 -520);
PAINT GREEN (-1845 -520);
DISPLAY INVISIBLE (-1845 -520);
FORCEPROP 0 LAST QPN DFHS56FR016
J 0
(-1900 -625);
DISPLAY 0.638298 (-1900 -625);
FORCEPROP 1 LAST MATERIAL NA
J 0
(-1875 -550);
DISPLAY 0.446809 (-1875 -550);
FORCEPROP 1 LAST LOCATION J90_CON
J 1
(-1895 -455);
DISPLAY 0.446809 (-1895 -455);
PAINT PINK (-1895 -455);
FORCEPROP 0 LASTPIN (-1900 -525) $PN 1
R 1
J 2
(-1910 -535);
DISPLAY 0.680851 (-1910 -535);
PAINT MONO (-1910 -535);
FORCEPROP 1 LAST PATH I69
J 1
(-1895 -430);
DISPLAY 0.446809 (-1895 -430);
PAINT GREEN (-1895 -430);
DISPLAY INVISIBLE (-1895 -430);
FORCEPROP 2 LAST CDS_LIB pure_quanta
J 0
(-1900 -475);
DISPLAY INVISIBLE (-1900 -475);
FORCEPROP 1 LASTPIN (-1900 -525) $PIN_NUMBER ?
J 2
(-1850 -525);
DISPLAY 0.702128 (-1850 -525);
PAINT MONO (-1850 -525);
DISPLAY INVISIBLE (-1850 -525);
FORCEPROP 1 LAST PACK_TYPE TP_BOM ONLY
J 1
(-1845 -540);
DISPLAY 0.446809 (-1845 -540);
PAINT GREEN (-1845 -540);
DISPLAY INVISIBLE (-1845 -540);
FORCEPROP 0 LAST $SEC 1
J 0
(-1875 -425);
DISPLAY 0.680851 (-1875 -425);
PAINT MONO (-1875 -425);
DISPLAY INVISIBLE (-1875 -425);
FORCEPROP 0 LAST CDS_SEC 1
J 0
(-1875 -425);
DISPLAY 1.021277 (-1875 -425);
DISPLAY INVISIBLE (-1875 -425);
FORCEADD TP..1
(-1225 -475);
FORCEPROP 1 LAST PART_NUMBER TP12_BOM
J 1
(-1170 -520);
DISPLAY 0.446809 (-1170 -520);
PAINT GREEN (-1170 -520);
DISPLAY INVISIBLE (-1170 -520);
FORCEPROP 1 LAST MATERIAL NA
J 0
(-1200 -550);
DISPLAY 0.446809 (-1200 -550);
FORCEPROP 0 LAST QPN DEJP0020021
J 0
(-1225 -625);
DISPLAY 0.638298 (-1225 -625);
FORCEPROP 1 LAST LOCATION JP4003_12
J 1
(-1220 -455);
DISPLAY 0.446809 (-1220 -455);
PAINT PINK (-1220 -455);
FORCEPROP 0 LASTPIN (-1225 -525) $PN 1
R 1
J 2
(-1235 -535);
DISPLAY 0.680851 (-1235 -535);
PAINT MONO (-1235 -535);
FORCEPROP 1 LAST PATH I70
J 1
(-1220 -430);
DISPLAY 0.446809 (-1220 -430);
PAINT GREEN (-1220 -430);
DISPLAY INVISIBLE (-1220 -430);
FORCEPROP 1 LAST PACK_TYPE TP_BOM ONLY
J 1
(-1170 -540);
DISPLAY 0.446809 (-1170 -540);
PAINT GREEN (-1170 -540);
DISPLAY INVISIBLE (-1170 -540);
FORCEPROP 1 LASTPIN (-1225 -525) $PIN_NUMBER ?
J 2
(-1175 -525);
DISPLAY 0.702128 (-1175 -525);
PAINT MONO (-1175 -525);
DISPLAY INVISIBLE (-1175 -525);
FORCEPROP 2 LAST CDS_LIB pure_quanta
J 0
(-1225 -475);
DISPLAY INVISIBLE (-1225 -475);
FORCEPROP 0 LAST $SEC 1
J 0
(-1200 -425);
DISPLAY 0.680851 (-1200 -425);
PAINT MONO (-1200 -425);
DISPLAY INVISIBLE (-1200 -425);
FORCEPROP 0 LAST CDS_SEC 1
J 0
(-1200 -425);
DISPLAY 1.021277 (-1200 -425);
DISPLAY INVISIBLE (-1200 -425);
FORCEADD TP..1
(-1225 -775);
FORCEPROP 1 LAST PART_NUMBER TP12_BOM
J 1
(-1170 -820);
DISPLAY 0.446809 (-1170 -820);
PAINT GREEN (-1170 -820);
DISPLAY INVISIBLE (-1170 -820);
FORCEPROP 1 LAST MATERIAL NA
J 0
(-1200 -850);
DISPLAY 0.446809 (-1200 -850);
FORCEPROP 0 LAST QPN DEJP0020021
J 0
(-1225 -925);
DISPLAY 0.638298 (-1225 -925);
FORCEPROP 1 LAST LOCATION JP15_23
J 1
(-1220 -755);
DISPLAY 0.446809 (-1220 -755);
PAINT PINK (-1220 -755);
FORCEPROP 0 LASTPIN (-1225 -825) $PN 1
R 1
J 2
(-1235 -835);
DISPLAY 0.680851 (-1235 -835);
PAINT MONO (-1235 -835);
FORCEPROP 1 LAST PATH I71
J 1
(-1220 -730);
DISPLAY 0.446809 (-1220 -730);
PAINT GREEN (-1220 -730);
DISPLAY INVISIBLE (-1220 -730);
FORCEPROP 2 LAST CDS_LIB pure_quanta
J 0
(-1225 -775);
DISPLAY INVISIBLE (-1225 -775);
FORCEPROP 1 LASTPIN (-1225 -825) $PIN_NUMBER ?
J 2
(-1175 -825);
DISPLAY 0.702128 (-1175 -825);
PAINT MONO (-1175 -825);
DISPLAY INVISIBLE (-1175 -825);
FORCEPROP 1 LAST PACK_TYPE TP_BOM ONLY
J 1
(-1170 -840);
DISPLAY 0.446809 (-1170 -840);
PAINT GREEN (-1170 -840);
DISPLAY INVISIBLE (-1170 -840);
FORCEPROP 0 LAST $SEC 1
J 0
(-1200 -725);
DISPLAY 0.680851 (-1200 -725);
PAINT MONO (-1200 -725);
DISPLAY INVISIBLE (-1200 -725);
FORCEPROP 0 LAST CDS_SEC 1
J 0
(-1200 -725);
DISPLAY 1.021277 (-1200 -725);
DISPLAY INVISIBLE (-1200 -725);
FORCEADD TP..1
(-1225 -1075);
FORCEPROP 1 LAST PART_NUMBER TP12_BOM
J 1
(-1170 -1120);
DISPLAY 0.446809 (-1170 -1120);
PAINT GREEN (-1170 -1120);
DISPLAY INVISIBLE (-1170 -1120);
FORCEPROP 0 LAST QPN DEJP0020021
J 0
(-1225 -1225);
DISPLAY 0.638298 (-1225 -1225);
FORCEPROP 1 LAST MATERIAL NA
J 0
(-1200 -1150);
DISPLAY 0.446809 (-1200 -1150);
FORCEPROP 1 LAST LOCATION JP16_23
J 1
(-1220 -1055);
DISPLAY 0.446809 (-1220 -1055);
PAINT PINK (-1220 -1055);
FORCEPROP 0 LASTPIN (-1225 -1125) $PN 1
R 1
J 2
(-1235 -1135);
DISPLAY 0.680851 (-1235 -1135);
PAINT MONO (-1235 -1135);
FORCEPROP 1 LAST PATH I72
J 1
(-1220 -1030);
DISPLAY 0.446809 (-1220 -1030);
PAINT GREEN (-1220 -1030);
DISPLAY INVISIBLE (-1220 -1030);
FORCEPROP 1 LAST PACK_TYPE TP_BOM ONLY
J 1
(-1170 -1140);
DISPLAY 0.446809 (-1170 -1140);
PAINT GREEN (-1170 -1140);
DISPLAY INVISIBLE (-1170 -1140);
FORCEPROP 1 LASTPIN (-1225 -1125) $PIN_NUMBER ?
J 2
(-1175 -1125);
DISPLAY 0.702128 (-1175 -1125);
PAINT MONO (-1175 -1125);
DISPLAY INVISIBLE (-1175 -1125);
FORCEPROP 2 LAST CDS_LIB pure_quanta
J 0
(-1225 -1075);
DISPLAY INVISIBLE (-1225 -1075);
FORCEPROP 0 LAST $SEC 1
J 0
(-1200 -1025);
DISPLAY 0.680851 (-1200 -1025);
PAINT MONO (-1200 -1025);
DISPLAY INVISIBLE (-1200 -1025);
FORCEPROP 0 LAST CDS_SEC 1
J 0
(-1200 -1025);
DISPLAY 1.021277 (-1200 -1025);
DISPLAY INVISIBLE (-1200 -1025);
FORCEADD ME_DUMMY_SYMBOL..1
(3625 4300);
FORCEPROP 1 LAST PART_NUMBER DUMMY46
J 0
(3431 4497);
DISPLAY 0.723404 (3431 4497);
PAINT GREEN (3431 4497);
DISPLAY INVISIBLE (3431 4497);
FORCEPROP 1 LAST MATERIAL EMPTY
J 0
(3431 4432);
DISPLAY 0.723404 (3431 4432);
PAINT GREEN (3431 4432);
FORCEPROP 2 LAST VALUE SNLABEL_27X6
J 0
(3450 4600);
DISPLAY 1.021277 (3450 4600);
FORCEPROP 2 LAST PART_TYPE MECH
J 0
(3450 4650);
DISPLAY 1.021277 (3450 4650);
FORCEPROP 1 LAST LOCATION ME22
J 0
(3431 4561);
DISPLAY 0.723404 (3431 4561);
PAINT GREEN (3431 4561);
FORCEPROP 2 LAST CDS_LIB pure_quanta
J 0
(3625 4300);
DISPLAY INVISIBLE (3625 4300);
FORCEPROP 1 LAST PATH I73
J 0
(3825 4175);
DISPLAY 0.723404 (3825 4175);
PAINT GREEN (3825 4175);
DISPLAY INVISIBLE (3825 4175);
FORCEPROP 1 LAST PIN_NAMES_ROTATE True
J 0
(3625 4300);
DISPLAY 0.489362 (3625 4300);
PAINT GREEN (3625 4300);
DISPLAY INVISIBLE (3625 4300);
FORCEPROP 1 LAST PIN_TEXT_VISIBLE True
J 0
(3625 4300);
DISPLAY 0.489362 (3625 4300);
PAINT GREEN (3625 4300);
DISPLAY INVISIBLE (3625 4300);
FORCEPROP 1 LAST NEEDS_NO_SIZE TRUE
J 0
(3825 4232);
DISPLAY 0.723404 (3825 4232);
PAINT GREEN (3825 4232);
DISPLAY INVISIBLE (3825 4232);
FORCEPROP 1 LAST CDS_LMAN_SYM_OUTLINE -200,125,200,-125
J 0
(3625 4300);
DISPLAY 0.468085 (3625 4300);
PAINT GREEN (3625 4300);
DISPLAY INVISIBLE (3625 4300);
FORCEADD ME_DUMMY_SYMBOL..1
(-2800 1775);
FORCEPROP 1 LAST PART_NUMBER DUMMY47
J 0
(-2994 1972);
DISPLAY 0.723404 (-2994 1972);
PAINT GREEN (-2994 1972);
DISPLAY INVISIBLE (-2994 1972);
FORCEPROP 1 LAST MATERIAL EMPTY
J 0
(-2994 1907);
DISPLAY 0.723404 (-2994 1907);
PAINT GREEN (-2994 1907);
FORCEPROP 2 LAST VALUE CBS_3X558-8
J 0
(-2975 2075);
DISPLAY 1.021277 (-2975 2075);
FORCEPROP 2 LAST PART_TYPE MECH
J 0
(-2975 2125);
DISPLAY 1.021277 (-2975 2125);
FORCEPROP 1 LAST $LOCATION ME27
J 0
(-2994 2036);
DISPLAY 0.723404 (-2994 2036);
PAINT GREEN (-2994 2036);
FORCEPROP 1 LAST PIN_NAMES_ROTATE True
J 0
(-2800 1775);
DISPLAY 0.489362 (-2800 1775);
PAINT GREEN (-2800 1775);
DISPLAY INVISIBLE (-2800 1775);
FORCEPROP 1 LAST PIN_TEXT_VISIBLE True
J 0
(-2800 1775);
DISPLAY 0.489362 (-2800 1775);
PAINT GREEN (-2800 1775);
DISPLAY INVISIBLE (-2800 1775);
FORCEPROP 1 LAST NEEDS_NO_SIZE TRUE
J 0
(-2600 1707);
DISPLAY 0.723404 (-2600 1707);
PAINT GREEN (-2600 1707);
DISPLAY INVISIBLE (-2600 1707);
FORCEPROP 1 LAST CDS_LMAN_SYM_OUTLINE -200,125,200,-125
J 0
(-2800 1775);
DISPLAY 0.468085 (-2800 1775);
PAINT GREEN (-2800 1775);
DISPLAY INVISIBLE (-2800 1775);
FORCEPROP 1 LAST PATH I74
J 0
(-2600 1650);
DISPLAY 0.723404 (-2600 1650);
PAINT GREEN (-2600 1650);
DISPLAY INVISIBLE (-2600 1650);
FORCEPROP 2 LAST CDS_LIB pure_quanta
J 0
(-2800 1775);
DISPLAY INVISIBLE (-2800 1775);
FORCEPROP 0 LAST CDS_LOCATION ME27
J 0
(-2975 2175);
DISPLAY 1.021277 (-2975 2175);
DISPLAY INVISIBLE (-2975 2175);
FORCEADD ME_DUMMY_SYMBOL..1
(-225 1800);
FORCEPROP 1 LAST PART_NUMBER DUMMY28_HCLU2002010
J 0
(-419 1997);
DISPLAY 0.723404 (-419 1997);
PAINT GREEN (-419 1997);
DISPLAY INVISIBLE (-419 1997);
FORCEPROP 2 LAST VALUE EFI BIOS LABEL
J 0
(-400 2100);
DISPLAY 1.021277 (-400 2100);
FORCEPROP 2 LAST PART_TYPE MECH
J 0
(-400 2150);
DISPLAY 1.021277 (-400 2150);
FORCEPROP 1 LAST MATERIAL EMPTY
J 0
(-419 1932);
DISPLAY 0.723404 (-419 1932);
PAINT GREEN (-419 1932);
FORCEPROP 1 LAST $LOCATION ME28
J 0
(-419 2061);
DISPLAY 0.723404 (-419 2061);
PAINT GREEN (-419 2061);
FORCEPROP 2 LAST CDS_LIB pure_quanta
J 0
(-225 1800);
DISPLAY INVISIBLE (-225 1800);
FORCEPROP 1 LAST PATH I75
J 0
(-25 1675);
DISPLAY 0.723404 (-25 1675);
PAINT GREEN (-25 1675);
DISPLAY INVISIBLE (-25 1675);
FORCEPROP 1 LAST PIN_NAMES_ROTATE True
J 0
(-225 1800);
DISPLAY 0.489362 (-225 1800);
PAINT GREEN (-225 1800);
DISPLAY INVISIBLE (-225 1800);
FORCEPROP 1 LAST PIN_TEXT_VISIBLE True
J 0
(-225 1800);
DISPLAY 0.489362 (-225 1800);
PAINT GREEN (-225 1800);
DISPLAY INVISIBLE (-225 1800);
FORCEPROP 1 LAST NEEDS_NO_SIZE TRUE
J 0
(-25 1732);
DISPLAY 0.723404 (-25 1732);
PAINT GREEN (-25 1732);
DISPLAY INVISIBLE (-25 1732);
FORCEPROP 1 LAST CDS_LMAN_SYM_OUTLINE -200,125,200,-125
J 0
(-225 1800);
DISPLAY 0.468085 (-225 1800);
PAINT GREEN (-225 1800);
DISPLAY INVISIBLE (-225 1800);
FORCEPROP 0 LAST CDS_LOCATION ME28
J 0
(-400 2200);
DISPLAY 1.021277 (-400 2200);
DISPLAY INVISIBLE (-400 2200);
FORCEADD ME_DUMMY_SYMBOL..1
(4250 4275);
FORCEPROP 1 LAST PART_NUMBER DUMMY36
J 0
(4056 4472);
DISPLAY 0.723404 (4056 4472);
PAINT GREEN (4056 4472);
DISPLAY INVISIBLE (4056 4472);
FORCEPROP 1 LAST MATERIAL EMPTY
J 0
(4056 4407);
DISPLAY 0.723404 (4056 4407);
PAINT GREEN (4056 4407);
FORCEPROP 2 LAST VALUE SNLABEL_15X5
J 0
(4075 4575);
DISPLAY 1.021277 (4075 4575);
FORCEPROP 2 LAST PART_TYPE MECH
J 0
(4075 4625);
DISPLAY 1.021277 (4075 4625);
FORCEPROP 1 LAST $LOCATION ME29
J 0
(4056 4536);
DISPLAY 0.723404 (4056 4536);
PAINT GREEN (4056 4536);
FORCEPROP 1 LAST CDS_LMAN_SYM_OUTLINE -200,125,200,-125
J 0
(4250 4275);
DISPLAY 0.468085 (4250 4275);
PAINT GREEN (4250 4275);
DISPLAY INVISIBLE (4250 4275);
FORCEPROP 1 LAST NEEDS_NO_SIZE TRUE
J 0
(4450 4207);
DISPLAY 0.723404 (4450 4207);
PAINT GREEN (4450 4207);
DISPLAY INVISIBLE (4450 4207);
FORCEPROP 1 LAST PIN_TEXT_VISIBLE True
J 0
(4250 4275);
DISPLAY 0.489362 (4250 4275);
PAINT GREEN (4250 4275);
DISPLAY INVISIBLE (4250 4275);
FORCEPROP 1 LAST PIN_NAMES_ROTATE True
J 0
(4250 4275);
DISPLAY 0.489362 (4250 4275);
PAINT GREEN (4250 4275);
DISPLAY INVISIBLE (4250 4275);
FORCEPROP 1 LAST PATH I76
J 0
(4450 4150);
DISPLAY 0.723404 (4450 4150);
PAINT GREEN (4450 4150);
DISPLAY INVISIBLE (4450 4150);
FORCEPROP 2 LAST CDS_LIB pure_quanta
J 0
(4250 4275);
DISPLAY INVISIBLE (4250 4275);
FORCEPROP 0 LAST CDS_LOCATION ME29
J 0
(4075 4675);
DISPLAY 1.021277 (4075 4675);
DISPLAY INVISIBLE (4075 4675);
FORCEADD ME_DUMMY_SYMBOL..1
(4225 3275);
FORCEPROP 1 LAST PART_NUMBER DUMMY48
J 0
(4031 3472);
DISPLAY 0.723404 (4031 3472);
PAINT GREEN (4031 3472);
DISPLAY INVISIBLE (4031 3472);
FORCEPROP 2 LAST PART_TYPE MECH
J 0
(4050 3625);
DISPLAY 0.808511 (4050 3625);
FORCEPROP 1 LAST MATERIAL EMPTY
J 0
(4031 3407);
DISPLAY 0.723404 (4031 3407);
PAINT GREEN (4031 3407);
FORCEPROP 2 LAST VALUE PICKUP_SMDC20
J 0
(4050 3575);
DISPLAY 0.808511 (4050 3575);
FORCEPROP 1 LAST $LOCATION ME4
J 0
(4031 3536);
DISPLAY 0.723404 (4031 3536);
PAINT GREEN (4031 3536);
FORCEPROP 1 LAST PATH I9
J 0
(4425 3150);
DISPLAY 0.723404 (4425 3150);
PAINT GREEN (4425 3150);
DISPLAY INVISIBLE (4425 3150);
FORCEPROP 1 LAST PIN_NAMES_ROTATE True
J 0
(4225 3275);
DISPLAY 0.489362 (4225 3275);
PAINT GREEN (4225 3275);
DISPLAY INVISIBLE (4225 3275);
FORCEPROP 1 LAST PIN_TEXT_VISIBLE True
J 0
(4225 3275);
DISPLAY 0.489362 (4225 3275);
PAINT GREEN (4225 3275);
DISPLAY INVISIBLE (4225 3275);
FORCEPROP 1 LAST NEEDS_NO_SIZE TRUE
J 0
(4425 3207);
DISPLAY 0.723404 (4425 3207);
PAINT GREEN (4425 3207);
DISPLAY INVISIBLE (4425 3207);
FORCEPROP 1 LAST CDS_LMAN_SYM_OUTLINE -200,125,200,-125
J 0
(4225 3275);
DISPLAY 0.468085 (4225 3275);
PAINT GREEN (4225 3275);
DISPLAY INVISIBLE (4225 3275);
FORCEPROP 2 LAST CDS_LIB pure_quanta
J 0
(4225 3275);
PAINT MONO (4225 3275);
DISPLAY INVISIBLE (4225 3275);
FORCEPROP 1 LAST $LOCATION ME4
J 0
(4050 3675);
DISPLAY 1.021277 (4050 3675);
DISPLAY INVISIBLE (4050 3675);
FORCEPROP 2 LAST CDS_LOCATION ME4
J 0
(4050 3675);
DISPLAY 1.021277 (4050 3675);
DISPLAY INVISIBLE (4050 3675);
FORCEADD QUANTA_TITLE_BLOCK_C..3
(6025 -1500);
FORCEPROP 0 LAST CDS_CON_LAST_MODIFIED Fri Aug 25 14:05:34 2023
J 0
(4140 -1485);
PAINT MONO (4140 -1485);
DISPLAY INVISIBLE (4140 -1485);
FORCEPROP 1 LAST CUSTOM_TXT_CDS <CON_LAST_MODIFIED>
J 0
(4140 -1485);
DISPLAY 0.978723 (4140 -1485);
FORCEPROP 2 LAST CUSTOM_TXT_CDS <XR_PAGE_TITLE>
J 0
(-1865 3750);
DISPLAY 0.638298 (-1865 3750);
PAINT PINK (-1865 3750);
DISPLAY INVISIBLE (-1865 3750);
FORCEPROP 1 LAST CUSTOM_TXT_CDS <NAME_2>
J 0
(2850 -1450);
FORCEPROP 1 LAST CUSTOM_TXT_CDS <NAME_1>
J 0
(2850 -1325);
FORCEPROP 1 LAST CUSTOM_TXT_CDS <Q_NUMBER>
J 0
(4622 -1397);
DISPLAY 1.212766 (4622 -1397);
FORCEPROP 1 LAST CUSTOM_TXT_CDS <Q_PROJ>
J 0
(3643 -1398);
DISPLAY 1.212766 (3643 -1398);
FORCEPROP 1 LAST CUSTOM_TXT_CDS <Q_REV>
J 0
(5841 -1397);
DISPLAY 1.212766 (5841 -1397);
FORCEPROP 1 LAST CUSTOM_TXT_CDS <CON_PAGE_NUM> OF <CON_TOTAL_PAGES>
J 0
(5579 -1482);
DISPLAY 0.978723 (5579 -1482);
FORCEPROP 1 LAST Q_TITLE DUMMY SYMBOL
J 0
(-3341 -1474);
DISPLAY 2.446809 (-3341 -1474);
PAINT GREEN (-3341 -1474);
FORCEPROP 1 LAST Q_DEPT 
J 1
(2262 -1451);
DISPLAY 1.957447 (2262 -1451);
PAINT GREEN (2262 -1451);
FORCEPROP 2 LAST CDS_XR_PAGE_TITLE CR-311 : @S9S_MB_2U_LIB.S9S_MB_2U(SCH_1):PAGE311
J 0
(-1865 3750);
DISPLAY 0.638298 (-1865 3750);
PAINT PINK (-1865 3750);
DISPLAY INVISIBLE (-1865 3750);
FORCEPROP 2 LAST CDS_LIB pure_quanta
J 0
(6025 -1500);
PAINT MONO (6025 -1500);
DISPLAY INVISIBLE (6025 -1500);
FORCEPROP 1 LAST CDS_LMAN_SYM_OUTLINE -9475,6775,100,-125
J 0
(6025 -1500);
DISPLAY 0.468085 (6025 -1500);
PAINT GREEN (6025 -1500);
DISPLAY INVISIBLE (6025 -1500);
FORCEPROP 2 LAST PAGE_BORDER TRUE
J 0
(-1865 3750);
DISPLAY 0.638298 (-1865 3750);
PAINT PINK (-1865 3750);
DISPLAY INVISIBLE (-1865 3750);
FORCEPROP 1 LAST COMMENT_BODY TRUE
J 0
(6037 -1513);
DISPLAY 0.978723 (6037 -1513);
PAINT GREEN (6037 -1513);
DISPLAY INVISIBLE (6037 -1513);
FORCENOTE
CPU BACKPLANE
(-425 450) 0;
DISPLAY LEFT (-425 450);
DISPLAY 1.021277 (-425 450);
PAINT WHITE (-425 450);
FORCENOTE
FBPN+VPN
(3700 4925) 0;
DISPLAY LEFT (3700 4925);
DISPLAY 1.276596 (3700 4925);
PAINT WHITE (3700 4925);
FORCENOTE
NUT
(-299 2704) 0;
DISPLAY LEFT (-299 2704);
DISPLAY 3.148936 (-299 2704);
PAINT WHITE (-299 2704);
FORCENOTE
JUMPER
(-1350 -350) 0;
DISPLAY LEFT (-1350 -350);
DISPLAY 1.021277 (-1350 -350);
PAINT WHITE (-1350 -350);
FORCENOTE
CPU DUST COVER
(900 450) 0;
DISPLAY LEFT (900 450);
DISPLAY 1.021277 (900 450);
PAINT WHITE (900 450);
FORCENOTE
E1.S
(-1950 -350) 0;
DISPLAY LEFT (-1950 -350);
DISPLAY 1.021277 (-1950 -350);
PAINT WHITE (-1950 -350);
FORCENOTE
EFI BIOS LABEL
(-450 2275) 0;
DISPLAY LEFT (-450 2275);
DISPLAY 1.021277 (-450 2275);
PAINT WHITE (-450 2275);
FORCENOTE
CPU BOLSTER
(-425 1000) 0;
DISPLAY LEFT (-425 1000);
DISPLAY 1.021277 (-425 1000);
PAINT WHITE (-425 1000);
QUIT
